(kicad_pcb
	(version 20260206)
	(generator "pcbnew")
	(generator_version "10.0")
	(general
		(thickness 1.6)
		(legacy_teardrops no)
	)
	(paper "A4")
	(title_block
		(title "peb — Lightning_PEB_BRD.brd")
		(comment 1 "Lightning (Wiwynn / Facebook NVMe JBOF) / footprints 441-447 of 2563")
	)
	(layers
		(0 "F.Cu" signal "TOP")
		(4 "In1.Cu" signal "L2GND")
		(6 "In2.Cu" signal "L3")
		(8 "In3.Cu" signal "L4VCC")
		(10 "In4.Cu" signal "L5VCC")
		(12 "In5.Cu" signal "L6")
		(14 "In6.Cu" signal "L7GND")
		(2 "B.Cu" signal "BOTTOM")
		(9 "F.Adhes" user "F.Adhesive")
		(11 "B.Adhes" user "B.Adhesive")
		(13 "F.Paste" user "Package Geometry/Pastemask Top")
		(15 "B.Paste" user "Package Geometry/Pastemask Bottom")
		(5 "F.SilkS" user "Ref Des/Silkscreen Top")
		(7 "B.SilkS" user "Ref Des/Silkscreen Bottom")
		(1 "F.Mask" user "Board Geometry/Soldermask Top")
		(3 "B.Mask" user "Board Geometry/Soldermask Bottom")
		(17 "Dwgs.User" user "User.Drawings")
		(19 "Cmts.User" user "User.Comments")
		(21 "Eco1.User" user "User.Eco1")
		(23 "Eco2.User" user "User.Eco2")
		(25 "Edge.Cuts" user "Board Geometry/Outline")
		(27 "Margin" user)
		(31 "F.CrtYd" user "Package Geometry/Place Bound Top")
		(29 "B.CrtYd" user "Package Geometry/Place Bound Bottom")
		(35 "F.Fab" user "Ref Des/Assembly Top")
		(33 "B.Fab" user "Ref Des/Assembly Bottom")
	)
	(footprint ""
		(layer "F.Cu")
		(at 51.816 -191.262 180)
		(property "Reference" "R893"
			(at 0 0 180)
			(layer "F.SilkS")
			(hide yes)
			(effects
				(font
					(size 1.27 1.27)
				)
			)
		)
		(property "Value" "0R2J-2-GP"
			(at 0.064008 -3.993896 180)
			(unlocked yes)
			(layer "F.Fab")
			(hide yes)
			(effects
				(font
					(size 1.016 1.016)
					(thickness 0.1524)
				)
			)
		)
		(property "Device Type" "R402H16"
			(at 0.064008 -5.517896 180)
			(unlocked yes)
			(layer "F.Fab")
			(hide yes)
			(effects
				(font
					(size 1.016 1.016)
					(thickness 0.1524)
				)
			)
		)
		(duplicate_pad_numbers_are_jumpers no)
		(fp_line
			(start 0.508 -0.9398)
			(end -0.508 -0.9398)
			(stroke
				(width 0.1524)
				(type default)
			)
			(layer "F.SilkS")
		)
		(fp_line
			(start -0.508 -0.9398)
			(end -0.508 0.9398)
			(stroke
				(width 0.1524)
				(type default)
			)
			(layer "F.SilkS")
		)
		(fp_rect
			(start -0.508 0.9398)
			(end 0.508 -0.9398)
			(stroke
				(width 0)
				(type default)
			)
			(fill no)
			(layer "F.CrtYd")
		)
		(fp_rect
			(start -0.508 0.9398)
			(end 0.508 -0.9398)
			(stroke
				(width 0)
				(type default)
			)
			(fill no)
			(layer "F.Fab")
		)
		(pad "1" smd custom
			(at 0 -0.4445 180)
			(size 0.1397 0.1397)
			(layers "F.Cu" "F.Mask" "F.Paste")
			(net "BMC_I2C7_B_DBP_SCL")
			(options
				(clearance outline)
				(anchor circle)
			)
			(primitives
				(gr_poly
					(pts
						(arc
							(start -0.1778 -0.2794)
							(mid -0.249642 -0.249642)
							(end -0.2794 -0.1778)
						)
						(arc
							(start -0.2794 0.1778)
							(mid -0.249642 0.249642)
							(end -0.1778 0.2794)
						)
						(arc
							(start 0.1778 0.2794)
							(mid 0.249642 0.249642)
							(end 0.2794 0.1778)
						)
						(arc
							(start 0.2794 -0.1778)
							(mid 0.249642 -0.249642)
							(end 0.1778 -0.2794)
						)
					)
					(width 0)
					(fill yes)
				)
			)
		)
		(pad "2" smd custom
			(at 0 0.4445 180)
			(size 0.1397 0.1397)
			(layers "F.Cu" "F.Mask" "F.Paste")
			(net "BMC_I2C7_B_DBP_SCL_R")
			(options
				(clearance outline)
				(anchor circle)
			)
			(primitives
				(gr_poly
					(pts
						(arc
							(start -0.1778 -0.2794)
							(mid -0.249642 -0.249642)
							(end -0.2794 -0.1778)
						)
						(arc
							(start -0.2794 0.1778)
							(mid -0.249642 0.249642)
							(end -0.1778 0.2794)
						)
						(arc
							(start 0.1778 0.2794)
							(mid 0.249642 0.249642)
							(end 0.2794 0.1778)
						)
						(arc
							(start 0.2794 -0.1778)
							(mid 0.249642 -0.249642)
							(end 0.1778 -0.2794)
						)
					)
					(width 0)
					(fill yes)
				)
			)
		)
	)
	(footprint ""
		(layer "F.Cu")
		(at 178.9938 -71.628 180)
		(property "Reference" "C558"
			(at 0 0 180)
			(layer "F.SilkS")
			(hide yes)
			(effects
				(font
					(size 1.27 1.27)
				)
			)
		)
		(property "Value" "SC4D7U16V5KX-1-GP"
			(at -0.0762 -6.1214 180)
			(unlocked yes)
			(layer "F.Fab")
			(hide yes)
			(effects
				(font
					(size 1.016 1.016)
					(thickness 0.1524)
				)
			)
		)
		(property "Device Type" "C805H56"
			(at -0.0762 -8.1534 180)
			(unlocked yes)
			(layer "F.Fab")
			(hide yes)
			(effects
				(font
					(size 1.016 1.016)
					(thickness 0.1524)
				)
			)
		)
		(duplicate_pad_numbers_are_jumpers no)
		(fp_line
			(start 0.635 0)
			(end -0.635 0)
			(stroke
				(width 0.508)
				(type default)
			)
			(layer "F.SilkS")
		)
		(fp_rect
			(start -0.9652 1.778)
			(end 0.9652 -1.778)
			(stroke
				(width 0)
				(type default)
			)
			(fill no)
			(layer "F.CrtYd")
		)
		(fp_poly
			(pts
				(xy -0.9652 -1.778) (xy 0.9652 -1.778) (xy 0.9652 1.778) (xy -0.9652 1.778)
			)
			(stroke
				(width 0)
				(type default)
			)
			(fill no)
			(layer "F.Fab")
		)
		(pad "1" smd rect
			(at 0 -0.9652 180)
			(size 1.397 1.143)
			(layers "F.Cu" "F.Mask" "F.Paste")
			(net "DUT_AVD_PCIE")
		)
		(pad "2" smd rect
			(at 0 0.9652 180)
			(size 1.397 1.143)
			(layers "F.Cu" "F.Mask" "F.Paste")
			(net "GND")
		)
	)
	(footprint ""
		(layer "F.Cu")
		(at 65.532 -131.953)
		(property "Reference" "R5764"
			(at 0 0 0)
			(layer "F.SilkS")
			(hide yes)
			(effects
				(font
					(size 1.27 1.27)
				)
			)
		)
		(property "Value" "5K6R2F-2-GP"
			(at 0.064008 -3.993896 0)
			(unlocked yes)
			(layer "F.Fab")
			(hide yes)
			(effects
				(font
					(size 1.016 1.016)
					(thickness 0.1524)
				)
			)
		)
		(property "Device Type" "R402H16"
			(at 0.064008 -5.517896 0)
			(unlocked yes)
			(layer "F.Fab")
			(hide yes)
			(effects
				(font
					(size 1.016 1.016)
					(thickness 0.1524)
				)
			)
		)
		(duplicate_pad_numbers_are_jumpers no)
		(fp_line
			(start -0.508 -0.9398)
			(end -0.508 0.9398)
			(stroke
				(width 0.1524)
				(type default)
			)
			(layer "F.SilkS")
		)
		(fp_line
			(start 0.508 -0.9398)
			(end -0.508 -0.9398)
			(stroke
				(width 0.1524)
				(type default)
			)
			(layer "F.SilkS")
		)
		(fp_rect
			(start -0.508 0.9398)
			(end 0.508 -0.9398)
			(stroke
				(width 0)
				(type default)
			)
			(fill no)
			(layer "F.CrtYd")
		)
		(fp_rect
			(start -0.508 0.9398)
			(end 0.508 -0.9398)
			(stroke
				(width 0)
				(type default)
			)
			(fill no)
			(layer "F.Fab")
		)
		(pad "1" smd custom
			(at 0 -0.4445)
			(size 0.1397 0.1397)
			(layers "F.Cu" "F.Mask" "F.Paste")
			(net "P12V")
			(options
				(clearance outline)
				(anchor circle)
			)
			(primitives
				(gr_poly
					(pts
						(arc
							(start -0.1778 -0.2794)
							(mid -0.249642 -0.249642)
							(end -0.2794 -0.1778)
						)
						(arc
							(start -0.2794 0.1778)
							(mid -0.249642 0.249642)
							(end -0.1778 0.2794)
						)
						(arc
							(start 0.1778 0.2794)
							(mid 0.249642 0.249642)
							(end 0.2794 0.1778)
						)
						(arc
							(start 0.2794 -0.1778)
							(mid 0.249642 -0.249642)
							(end 0.1778 -0.2794)
						)
					)
					(width 0)
					(fill yes)
				)
			)
		)
		(pad "2" smd custom
			(at 0 0.4445)
			(size 0.1397 0.1397)
			(layers "F.Cu" "F.Mask" "F.Paste")
			(net "ADC_12V")
			(options
				(clearance outline)
				(anchor circle)
			)
			(primitives
				(gr_poly
					(pts
						(arc
							(start -0.1778 -0.2794)
							(mid -0.249642 -0.249642)
							(end -0.2794 -0.1778)
						)
						(arc
							(start -0.2794 0.1778)
							(mid -0.249642 0.249642)
							(end -0.1778 0.2794)
						)
						(arc
							(start 0.1778 0.2794)
							(mid 0.249642 0.249642)
							(end 0.2794 0.1778)
						)
						(arc
							(start 0.2794 -0.1778)
							(mid 0.249642 -0.249642)
							(end 0.1778 -0.2794)
						)
					)
					(width 0)
					(fill yes)
				)
			)
		)
	)
	(footprint ""
		(layer "F.Cu")
		(at 129.466086 -51.351688 -90)
		(property "Reference" "R946"
			(at 0 0 270)
			(layer "F.SilkS")
			(hide yes)
			(effects
				(font
					(size 1.27 1.27)
				)
			)
		)
		(property "Value" "0R2J-2-GP"
			(at 0.064008 -3.993896 270)
			(unlocked yes)
			(layer "F.Fab")
			(hide yes)
			(effects
				(font
					(size 1.016 1.016)
					(thickness 0.1524)
				)
			)
		)
		(property "Device Type" "R402H16"
			(at 0.064008 -5.517896 270)
			(unlocked yes)
			(layer "F.Fab")
			(hide yes)
			(effects
				(font
					(size 1.016 1.016)
					(thickness 0.1524)
				)
			)
		)
		(duplicate_pad_numbers_are_jumpers no)
		(fp_line
			(start -0.508 -0.9398)
			(end -0.508 0.9398)
			(stroke
				(width 0.1524)
				(type default)
			)
			(layer "F.SilkS")
		)
		(fp_line
			(start 0.508 -0.9398)
			(end -0.508 -0.9398)
			(stroke
				(width 0.1524)
				(type default)
			)
			(layer "F.SilkS")
		)
		(fp_rect
			(start -0.508 0.9398)
			(end 0.508 -0.9398)
			(stroke
				(width 0)
				(type default)
			)
			(fill no)
			(layer "F.CrtYd")
		)
		(fp_rect
			(start -0.508 0.9398)
			(end 0.508 -0.9398)
			(stroke
				(width 0)
				(type default)
			)
			(fill no)
			(layer "F.Fab")
		)
		(pad "1" smd custom
			(at 0 -0.4445 270)
			(size 0.1397 0.1397)
			(layers "F.Cu" "F.Mask" "F.Paste")
			(net "PMC_R_RXD5")
			(options
				(clearance outline)
				(anchor circle)
			)
			(primitives
				(gr_poly
					(pts
						(arc
							(start -0.1778 -0.2794)
							(mid -0.249642 -0.249642)
							(end -0.2794 -0.1778)
						)
						(arc
							(start -0.2794 0.1778)
							(mid -0.249642 0.249642)
							(end -0.1778 0.2794)
						)
						(arc
							(start 0.1778 0.2794)
							(mid 0.249642 0.249642)
							(end 0.2794 0.1778)
						)
						(arc
							(start 0.2794 -0.1778)
							(mid 0.249642 -0.249642)
							(end 0.1778 -0.2794)
						)
					)
					(width 0)
					(fill yes)
				)
			)
		)
		(pad "2" smd custom
			(at 0 0.4445 270)
			(size 0.1397 0.1397)
			(layers "F.Cu" "F.Mask" "F.Paste")
			(net "EXP_SMART_RX")
			(options
				(clearance outline)
				(anchor circle)
			)
			(primitives
				(gr_poly
					(pts
						(arc
							(start -0.1778 -0.2794)
							(mid -0.249642 -0.249642)
							(end -0.2794 -0.1778)
						)
						(arc
							(start -0.2794 0.1778)
							(mid -0.249642 0.249642)
							(end -0.1778 0.2794)
						)
						(arc
							(start 0.1778 0.2794)
							(mid 0.249642 0.249642)
							(end 0.2794 0.1778)
						)
						(arc
							(start 0.2794 -0.1778)
							(mid 0.249642 -0.249642)
							(end 0.1778 -0.2794)
						)
					)
					(width 0)
					(fill yes)
				)
			)
		)
	)
	(footprint ""
		(layer "F.Cu")
		(at 238.252 -6.35)
		(property "Reference" "R173"
			(at 0 0 0)
			(layer "F.SilkS")
			(hide yes)
			(effects
				(font
					(size 1.27 1.27)
				)
			)
		)
		(property "Value" "4K7R2F-GP"
			(at 0.064008 -3.993896 0)
			(unlocked yes)
			(layer "F.Fab")
			(hide yes)
			(effects
				(font
					(size 1.016 1.016)
					(thickness 0.1524)
				)
			)
		)
		(property "Device Type" "R402H16"
			(at 0.064008 -5.517896 0)
			(unlocked yes)
			(layer "F.Fab")
			(hide yes)
			(effects
				(font
					(size 1.016 1.016)
					(thickness 0.1524)
				)
			)
		)
		(duplicate_pad_numbers_are_jumpers no)
		(fp_line
			(start -0.508 -0.9398)
			(end -0.508 0.9398)
			(stroke
				(width 0.1524)
				(type default)
			)
			(layer "F.SilkS")
		)
		(fp_line
			(start 0.508 -0.9398)
			(end -0.508 -0.9398)
			(stroke
				(width 0.1524)
				(type default)
			)
			(layer "F.SilkS")
		)
		(fp_rect
			(start -0.508 0.9398)
			(end 0.508 -0.9398)
			(stroke
				(width 0)
				(type default)
			)
			(fill no)
			(layer "F.CrtYd")
		)
		(fp_rect
			(start -0.508 0.9398)
			(end 0.508 -0.9398)
			(stroke
				(width 0)
				(type default)
			)
			(fill no)
			(layer "F.Fab")
		)
		(pad "1" smd custom
			(at 0 -0.4445)
			(size 0.1397 0.1397)
			(layers "F.Cu" "F.Mask" "F.Paste")
			(net "P3V3_STBY")
			(options
				(clearance outline)
				(anchor circle)
			)
			(primitives
				(gr_poly
					(pts
						(arc
							(start -0.1778 -0.2794)
							(mid -0.249642 -0.249642)
							(end -0.2794 -0.1778)
						)
						(arc
							(start -0.2794 0.1778)
							(mid -0.249642 0.249642)
							(end -0.1778 0.2794)
						)
						(arc
							(start 0.1778 0.2794)
							(mid 0.249642 0.249642)
							(end 0.2794 0.1778)
						)
						(arc
							(start 0.2794 -0.1778)
							(mid 0.249642 -0.249642)
							(end 0.1778 -0.2794)
						)
					)
					(width 0)
					(fill yes)
				)
			)
		)
		(pad "2" smd custom
			(at 0 0.4445)
			(size 0.1397 0.1397)
			(layers "F.Cu" "F.Mask" "F.Paste")
			(net "UART_COUNT")
			(options
				(clearance outline)
				(anchor circle)
			)
			(primitives
				(gr_poly
					(pts
						(arc
							(start -0.1778 -0.2794)
							(mid -0.249642 -0.249642)
							(end -0.2794 -0.1778)
						)
						(arc
							(start -0.2794 0.1778)
							(mid -0.249642 0.249642)
							(end -0.1778 0.2794)
						)
						(arc
							(start 0.1778 0.2794)
							(mid 0.249642 0.249642)
							(end 0.2794 0.1778)
						)
						(arc
							(start 0.2794 -0.1778)
							(mid 0.249642 -0.249642)
							(end 0.1778 -0.2794)
						)
					)
					(width 0)
					(fill yes)
				)
			)
		)
	)
	(footprint ""
		(layer "F.Cu")
		(at 81.448148 -75.00366)
		(property "Reference" "R968"
			(at 0 0 0)
			(layer "F.SilkS")
			(hide yes)
			(effects
				(font
					(size 1.27 1.27)
				)
			)
		)
		(property "Value" "4K7R2F-GP"
			(at 0.064008 -3.993896 0)
			(unlocked yes)
			(layer "F.Fab")
			(hide yes)
			(effects
				(font
					(size 1.016 1.016)
					(thickness 0.1524)
				)
			)
		)
		(property "Device Type" "R402H16"
			(at 0.064008 -5.517896 0)
			(unlocked yes)
			(layer "F.Fab")
			(hide yes)
			(effects
				(font
					(size 1.016 1.016)
					(thickness 0.1524)
				)
			)
		)
		(duplicate_pad_numbers_are_jumpers no)
		(fp_line
			(start -0.508 -0.9398)
			(end -0.508 0.9398)
			(stroke
				(width 0.1524)
				(type default)
			)
			(layer "F.SilkS")
		)
		(fp_line
			(start 0.508 -0.9398)
			(end -0.508 -0.9398)
			(stroke
				(width 0.1524)
				(type default)
			)
			(layer "F.SilkS")
		)
		(fp_rect
			(start -0.508 0.9398)
			(end 0.508 -0.9398)
			(stroke
				(width 0)
				(type default)
			)
			(fill no)
			(layer "F.CrtYd")
		)
		(fp_rect
			(start -0.508 0.9398)
			(end 0.508 -0.9398)
			(stroke
				(width 0)
				(type default)
			)
			(fill no)
			(layer "F.Fab")
		)
		(pad "1" smd custom
			(at 0 -0.4445)
			(size 0.1397 0.1397)
			(layers "F.Cu" "F.Mask" "F.Paste")
			(net "P3V3_STBY")
			(options
				(clearance outline)
				(anchor circle)
			)
			(primitives
				(gr_poly
					(pts
						(arc
							(start -0.1778 -0.2794)
							(mid -0.249642 -0.249642)
							(end -0.2794 -0.1778)
						)
						(arc
							(start -0.2794 0.1778)
							(mid -0.249642 0.249642)
							(end -0.1778 0.2794)
						)
						(arc
							(start 0.1778 0.2794)
							(mid 0.249642 0.249642)
							(end 0.2794 0.1778)
						)
						(arc
							(start 0.2794 -0.1778)
							(mid 0.249642 -0.249642)
							(end 0.1778 -0.2794)
						)
					)
					(width 0)
					(fill yes)
				)
			)
		)
		(pad "2" smd custom
			(at 0 0.4445)
			(size 0.1397 0.1397)
			(layers "F.Cu" "F.Mask" "F.Paste")
			(net "SEC_RST_N_R")
			(options
				(clearance outline)
				(anchor circle)
			)
			(primitives
				(gr_poly
					(pts
						(arc
							(start -0.1778 -0.2794)
							(mid -0.249642 -0.249642)
							(end -0.2794 -0.1778)
						)
						(arc
							(start -0.2794 0.1778)
							(mid -0.249642 0.249642)
							(end -0.1778 0.2794)
						)
						(arc
							(start 0.1778 0.2794)
							(mid 0.249642 0.249642)
							(end 0.2794 0.1778)
						)
						(arc
							(start 0.2794 -0.1778)
							(mid 0.249642 -0.249642)
							(end 0.1778 -0.2794)
						)
					)
					(width 0)
					(fill yes)
				)
			)
		)
	)
	(footprint ""
		(layer "F.Cu")
		(at 14.605 -122.682 -90)
		(property "Reference" "R295"
			(at 0 0 270)
			(layer "F.SilkS")
			(hide yes)
			(effects
				(font
					(size 1.27 1.27)
				)
			)
		)
		(property "Value" "4K7R2F-GP"
			(at 0.064008 -3.993896 270)
			(unlocked yes)
			(layer "F.Fab")
			(hide yes)
			(effects
				(font
					(size 1.016 1.016)
					(thickness 0.1524)
				)
			)
		)
		(property "Device Type" "R402H16"
			(at 0.064008 -5.517896 270)
			(unlocked yes)
			(layer "F.Fab")
			(hide yes)
			(effects
				(font
					(size 1.016 1.016)
					(thickness 0.1524)
				)
			)
		)
		(duplicate_pad_numbers_are_jumpers no)
		(fp_line
			(start -0.508 -0.9398)
			(end -0.508 0.9398)
			(stroke
				(width 0.1524)
				(type default)
			)
			(layer "F.SilkS")
		)
		(fp_line
			(start 0.508 -0.9398)
			(end -0.508 -0.9398)
			(stroke
				(width 0.1524)
				(type default)
			)
			(layer "F.SilkS")
		)
		(fp_rect
			(start -0.508 0.9398)
			(end 0.508 -0.9398)
			(stroke
				(width 0)
				(type default)
			)
			(fill no)
			(layer "F.CrtYd")
		)
		(fp_rect
			(start -0.508 0.9398)
			(end 0.508 -0.9398)
			(stroke
				(width 0)
				(type default)
			)
			(fill no)
			(layer "F.Fab")
		)
		(pad "1" smd custom
			(at 0 -0.4445 270)
			(size 0.1397 0.1397)
			(layers "F.Cu" "F.Mask" "F.Paste")
			(net "P3V3_STBY")
			(options
				(clearance outline)
				(anchor circle)
			)
			(primitives
				(gr_poly
					(pts
						(arc
							(start -0.1778 -0.2794)
							(mid -0.249642 -0.249642)
							(end -0.2794 -0.1778)
						)
						(arc
							(start -0.2794 0.1778)
							(mid -0.249642 0.249642)
							(end -0.1778 0.2794)
						)
						(arc
							(start 0.1778 0.2794)
							(mid 0.249642 0.249642)
							(end 0.2794 0.1778)
						)
						(arc
							(start 0.2794 -0.1778)
							(mid 0.249642 -0.249642)
							(end 0.1778 -0.2794)
						)
					)
					(width 0)
					(fill yes)
				)
			)
		)
		(pad "2" smd custom
			(at 0 0.4445 270)
			(size 0.1397 0.1397)
			(layers "F.Cu" "F.Mask" "F.Paste")
			(net "I2C2_LS_G2")
			(options
				(clearance outline)
				(anchor circle)
			)
			(primitives
				(gr_poly
					(pts
						(arc
							(start -0.1778 -0.2794)
							(mid -0.249642 -0.249642)
							(end -0.2794 -0.1778)
						)
						(arc
							(start -0.2794 0.1778)
							(mid -0.249642 0.249642)
							(end -0.1778 0.2794)
						)
						(arc
							(start 0.1778 0.2794)
							(mid 0.249642 0.249642)
							(end 0.2794 0.1778)
						)
						(arc
							(start 0.2794 -0.1778)
							(mid 0.249642 -0.249642)
							(end 0.1778 -0.2794)
						)
					)
					(width 0)
					(fill yes)
				)
			)
		)
	)
)
